# S9S_MB_2U (Grand Teton) — schematic netlist excerpt (pin names and nets, part order shuffled) for the footprints in the layout excerpt that follows; sources: Cadence DE-HDL packaged netlist, KiCad conversion of 03242023_DA0F0TMBIJ0_F0T_Motherboard_J_brd_V01_OCP.brd

PR3986  Q_RES  2K 0.1% CHIP  pkg 0402LF  page 303 : A = HSC_CS_3 ; B = AGND_HSC
PR4272  Q_RES  0 5% CHIP  pkg 0402LF  page 300 : A = SW_PVNN_MAIN_CPU1_BST ; B = SW_PVNN_MAIN_CPU1_BST_R

(kicad_pcb
	(version 20260206)
	(generator "pcbnew")
	(generator_version "10.0")
	(general
		(thickness 1.6)
		(legacy_teardrops no)
	)
	(paper "A4")
	(title_block
		(title "03242023_DA0F0TMBIJ0_F0T_Motherboard_J_brd_V01_OCP.brd")
		(comment 1 "Grand Teton / footprints 2666-2667 of 6105")
	)
	(layers
		(0 "F.Cu" signal "TOP")
		(4 "In1.Cu" signal "GND")
		(6 "In2.Cu" signal "IN1")
		(8 "In3.Cu" signal "GND1")
		(10 "In4.Cu" signal "IN2")
		(12 "In5.Cu" signal "GND2")
		(14 "In6.Cu" signal "IN3")
		(16 "In7.Cu" signal "GND3")
		(18 "In8.Cu" signal "VCC")
		(20 "In9.Cu" signal "VCC1")
		(22 "In10.Cu" signal "GND4")
		(24 "In11.Cu" signal "IN4")
		(26 "In12.Cu" signal "GND5")
		(28 "In13.Cu" signal "IN5")
		(30 "In14.Cu" signal "GND6")
		(32 "In15.Cu" signal "IN6")
		(34 "In16.Cu" signal "GND7")
		(2 "B.Cu" signal "BOTTOM")
		(9 "F.Adhes" user "F.Adhesive")
		(11 "B.Adhes" user "B.Adhesive")
		(13 "F.Paste" user "Package Geometry/Pastemask Top")
		(15 "B.Paste" user "Package Geometry/Pastemask Bottom")
		(5 "F.SilkS" user "Ref Des/Silkscreen Top")
		(7 "B.SilkS" user "Ref Des/Silkscreen Bottom")
		(1 "F.Mask" user "Board Geometry/Soldermask Top")
		(3 "B.Mask" user "Board Geometry/Soldermask Bottom")
		(17 "Dwgs.User" user "User.Drawings")
		(19 "Cmts.User" user "User.Comments")
		(21 "Eco1.User" user "User.Eco1")
		(23 "Eco2.User" user "User.Eco2")
		(25 "Edge.Cuts" user "Board Geometry/Outline")
		(27 "Margin" user)
		(31 "F.CrtYd" user "Package Geometry/Place Bound Top")
		(29 "B.CrtYd" user "Package Geometry/Place Bound Bottom")
		(35 "F.Fab" user "Ref Des/Assembly Top")
		(33 "B.Fab" user "Ref Des/Assembly Bottom")
	)
	(footprint ""
		(layer "F.Cu")
		(at 216.065608 -401.775422 180)
		(property "Reference" "PR3986"
			(at 0 0 180)
			(layer "F.SilkS")
			(hide yes)
			(effects
				(font
					(size 1.27 1.27)
				)
			)
		)
		(property "Value" ""
			(at 0 0 180)
			(layer "F.Fab")
			(effects
				(font
					(size 1.27 1.27)
				)
			)
		)
		(duplicate_pad_numbers_are_jumpers no)
		(fp_line
			(start 0.7874 0.4064)
			(end -0.7874 0.4064)
			(stroke
				(width 0.1524)
				(type default)
			)
			(layer "F.SilkS")
		)
		(fp_line
			(start 0.7874 -0.4064)
			(end 0.7874 0.4064)
			(stroke
				(width 0.1524)
				(type default)
			)
			(layer "F.SilkS")
		)
		(fp_line
			(start -0.7874 0.4064)
			(end -0.7874 -0.4064)
			(stroke
				(width 0.1524)
				(type default)
			)
			(layer "F.SilkS")
		)
		(fp_line
			(start -0.7874 -0.4064)
			(end 0.7874 -0.4064)
			(stroke
				(width 0.1524)
				(type default)
			)
			(layer "F.SilkS")
		)
		(fp_line
			(start 0.67945 0.3048)
			(end 0.120396 0.3048)
			(stroke
				(width 0.1)
				(type default)
			)
			(layer "F.Fab")
		)
		(fp_line
			(start 0.67945 -0.3048)
			(end 0.67945 0.3048)
			(stroke
				(width 0.1)
				(type default)
			)
			(layer "F.Fab")
		)
		(fp_line
			(start 0.12065 -0.2794)
			(end 0.12065 -0.3048)
			(stroke
				(width 0.1)
				(type default)
			)
			(layer "F.Fab")
		)
		(fp_line
			(start 0.12065 -0.3048)
			(end 0.67945 -0.3048)
			(stroke
				(width 0.1)
				(type default)
			)
			(layer "F.Fab")
		)
		(fp_line
			(start 0.120396 0.3048)
			(end 0.120396 0.2794)
			(stroke
				(width 0.1)
				(type default)
			)
			(layer "F.Fab")
		)
		(fp_line
			(start 0.120396 0.2794)
			(end -0.12065 0.2794)
			(stroke
				(width 0.1)
				(type default)
			)
			(layer "F.Fab")
		)
		(fp_line
			(start -0.12065 0.3048)
			(end -0.67945 0.3048)
			(stroke
				(width 0.1)
				(type default)
			)
			(layer "F.Fab")
		)
		(fp_line
			(start -0.12065 0.2794)
			(end -0.12065 0.3048)
			(stroke
				(width 0.1)
				(type default)
			)
			(layer "F.Fab")
		)
		(fp_line
			(start -0.12065 -0.2794)
			(end 0.12065 -0.2794)
			(stroke
				(width 0.1)
				(type default)
			)
			(layer "F.Fab")
		)
		(fp_line
			(start -0.12065 -0.305054)
			(end -0.12065 -0.2794)
			(stroke
				(width 0.1)
				(type default)
			)
			(layer "F.Fab")
		)
		(fp_line
			(start -0.67945 0.3048)
			(end -0.67945 -0.305054)
			(stroke
				(width 0.1)
				(type default)
			)
			(layer "F.Fab")
		)
		(fp_line
			(start -0.67945 -0.305054)
			(end -0.12065 -0.305054)
			(stroke
				(width 0.1)
				(type default)
			)
			(layer "F.Fab")
		)
		(pad "1" smd circle
			(at -0.40005 0 180)
			(size 0 0)
			(layers "F.Cu" "F.Mask" "F.Paste")
			(net "HSC_CS_3")
		)
		(pad "2" smd circle
			(at 0.40005 0 180)
			(size 0 0)
			(layers "F.Cu" "F.Mask" "F.Paste")
			(net "AGND_HSC")
		)
	)
	(footprint ""
		(layer "F.Cu")
		(at 25.636474 -178.759358 90)
		(property "Reference" "PR4272"
			(at 0 0 90)
			(layer "F.SilkS")
			(hide yes)
			(effects
				(font
					(size 1.27 1.27)
				)
			)
		)
		(property "Value" ""
			(at 0 0 90)
			(layer "F.Fab")
			(effects
				(font
					(size 1.27 1.27)
				)
			)
		)
		(duplicate_pad_numbers_are_jumpers no)
		(fp_line
			(start 0.7874 -0.4064)
			(end 0.7874 0.4064)
			(stroke
				(width 0.1524)
				(type default)
			)
			(layer "F.SilkS")
		)
		(fp_line
			(start -0.7874 -0.4064)
			(end 0.7874 -0.4064)
			(stroke
				(width 0.1524)
				(type default)
			)
			(layer "F.SilkS")
		)
		(fp_line
			(start 0.7874 0.4064)
			(end -0.7874 0.4064)
			(stroke
				(width 0.1524)
				(type default)
			)
			(layer "F.SilkS")
		)
		(fp_line
			(start -0.7874 0.4064)
			(end -0.7874 -0.4064)
			(stroke
				(width 0.1524)
				(type default)
			)
			(layer "F.SilkS")
		)
		(fp_line
			(start -0.12065 -0.305054)
			(end -0.12065 -0.2794)
			(stroke
				(width 0.1)
				(type default)
			)
			(layer "F.Fab")
		)
		(fp_line
			(start -0.67945 -0.305054)
			(end -0.12065 -0.305054)
			(stroke
				(width 0.1)
				(type default)
			)
			(layer "F.Fab")
		)
		(fp_line
			(start 0.67945 -0.3048)
			(end 0.67945 0.3048)
			(stroke
				(width 0.1)
				(type default)
			)
			(layer "F.Fab")
		)
		(fp_line
			(start 0.12065 -0.3048)
			(end 0.67945 -0.3048)
			(stroke
				(width 0.1)
				(type default)
			)
			(layer "F.Fab")
		)
		(fp_line
			(start 0.12065 -0.2794)
			(end 0.12065 -0.3048)
			(stroke
				(width 0.1)
				(type default)
			)
			(layer "F.Fab")
		)
		(fp_line
			(start -0.12065 -0.2794)
			(end 0.12065 -0.2794)
			(stroke
				(width 0.1)
				(type default)
			)
			(layer "F.Fab")
		)
		(fp_line
			(start 0.120396 0.2794)
			(end -0.12065 0.2794)
			(stroke
				(width 0.1)
				(type default)
			)
			(layer "F.Fab")
		)
		(fp_line
			(start -0.12065 0.2794)
			(end -0.12065 0.3048)
			(stroke
				(width 0.1)
				(type default)
			)
			(layer "F.Fab")
		)
		(fp_line
			(start 0.67945 0.3048)
			(end 0.120396 0.3048)
			(stroke
				(width 0.1)
				(type default)
			)
			(layer "F.Fab")
		)
		(fp_line
			(start 0.120396 0.3048)
			(end 0.120396 0.2794)
			(stroke
				(width 0.1)
				(type default)
			)
			(layer "F.Fab")
		)
		(fp_line
			(start -0.12065 0.3048)
			(end -0.67945 0.3048)
			(stroke
				(width 0.1)
				(type default)
			)
			(layer "F.Fab")
		)
		(fp_line
			(start -0.67945 0.3048)
			(end -0.67945 -0.305054)
			(stroke
				(width 0.1)
				(type default)
			)
			(layer "F.Fab")
		)
		(pad "1" smd circle
			(at -0.40005 0 90)
			(size 0 0)
			(layers "F.Cu" "F.Mask" "F.Paste")
			(net "SW_PVNN_MAIN_CPU1_BST")
		)
		(pad "2" smd circle
			(at 0.40005 0 90)
			(size 0 0)
			(layers "F.Cu" "F.Mask" "F.Paste")
			(net "SW_PVNN_MAIN_CPU1_BST_R")
		)
	)
)
